(kicad_pcb
	(version 20241229)
	(generator "pcbnew")
	(generator_version "9.0")
	(general
		(thickness 1.711)
		(legacy_teardrops no)
	)
	(paper "A4")
	(title_block
		(title "Antmicro Baseboard for Jetson AGX Thor")
		(date "2026-02-18")
		(rev "1.1.0")
		(company "Antmicro Ltd")
		(comment 1 "www.antmicro.com")
		(comment 9 "footprints 776-781 of 1170")
	)
	(layers
		(0 "F.Cu" signal)
		(4 "In1.Cu" signal)
		(6 "In2.Cu" signal)
		(8 "In3.Cu" signal)
		(10 "In4.Cu" jumper)
		(12 "In5.Cu" signal)
		(14 "In6.Cu" signal)
		(16 "In7.Cu" signal)
		(18 "In8.Cu" signal)
		(2 "B.Cu" signal)
		(9 "F.Adhes" user "F.Adhesive")
		(11 "B.Adhes" user "B.Adhesive")
		(13 "F.Paste" user)
		(15 "B.Paste" user)
		(5 "F.SilkS" user "F.Silkscreen")
		(7 "B.SilkS" user "B.Silkscreen")
		(1 "F.Mask" user)
		(3 "B.Mask" user)
		(17 "Dwgs.User" user "User.Drawings")
		(19 "Cmts.User" user "User.Comments")
		(21 "Eco1.User" user "User.Eco1")
		(23 "Eco2.User" user "User.Eco2")
		(25 "Edge.Cuts" user)
		(27 "Margin" user)
		(31 "F.CrtYd" user "F.Courtyard")
		(29 "B.CrtYd" user "B.Courtyard")
		(35 "F.Fab" user)
		(33 "B.Fab" user)
	)
	(footprint "antmicro-footprints:C_0402_1005Metric"
		(layer "B.Cu")
		(at 110.25 107.5)
		(descr "Capacitor SMD 0402")
		(tags "capacitor SMD 0402")
		(property "Reference" "C181"
			(at -0.95 0.5 180)
			(layer "B.SilkS")
			(effects
				(font
					(size 0.7 0.7)
					(thickness 0.15)
				)
				(justify left bottom mirror)
			)
		)
		(property "Value" "C_220n_0402"
			(at -1.022927 -2.155213 180)
			(layer "B.Fab")
			(effects
				(font
					(size 0.7 0.7)
					(thickness 0.15)
				)
				(justify left bottom mirror)
			)
		)
		(property "Datasheet" "https://www.yageo.com/en/Chart/Download/pdf/CC0402KRX5R6BB224"
			(at 0 0 180)
			(layer "B.Fab")
			(hide yes)
			(effects
				(font
					(size 1.27 1.27)
					(thickness 0.15)
				)
				(justify mirror)
			)
		)
		(property "Description" "SMD Multilayer Ceramic Capacitor, 0.22 µF, 10 V, 0402 [1005 Metric], ± 10%, X5R, CC Series"
			(at 0 0 180)
			(layer "B.Fab")
			(hide yes)
			(effects
				(font
					(size 1.27 1.27)
					(thickness 0.15)
				)
				(justify mirror)
			)
		)
		(property "MPN" "CC0402KRX5R6BB224"
			(at 0 0 0)
			(unlocked yes)
			(layer "B.Fab")
			(hide yes)
			(effects
				(font
					(size 1 1)
					(thickness 0.15)
				)
				(justify mirror)
			)
		)
		(property "Val" "220n"
			(at 0 0 0)
			(unlocked yes)
			(layer "B.Fab")
			(hide yes)
			(effects
				(font
					(size 1 1)
					(thickness 0.15)
				)
				(justify mirror)
			)
		)
		(property "Voltage" "25V"
			(at 0 0 0)
			(unlocked yes)
			(layer "B.Fab")
			(hide yes)
			(effects
				(font
					(size 1 1)
					(thickness 0.15)
				)
				(justify mirror)
			)
		)
		(property "Dielectric" "X7R"
			(at 0 0 0)
			(unlocked yes)
			(layer "B.Fab")
			(hide yes)
			(effects
				(font
					(size 1 1)
					(thickness 0.15)
				)
				(justify mirror)
			)
		)
		(property "Manufacturer" "YAGEO"
			(at 0 0 0)
			(unlocked yes)
			(layer "B.Fab")
			(hide yes)
			(effects
				(font
					(size 1 1)
					(thickness 0.15)
				)
				(justify mirror)
			)
		)
		(property "License" "Apache-2.0"
			(at 0 0 0)
			(unlocked yes)
			(layer "B.Fab")
			(hide yes)
			(effects
				(font
					(size 1 1)
					(thickness 0.15)
				)
				(justify mirror)
			)
		)
		(property "Author" "Antmicro"
			(at 0 0 0)
			(unlocked yes)
			(layer "B.Fab")
			(hide yes)
			(effects
				(font
					(size 1 1)
					(thickness 0.15)
				)
				(justify mirror)
			)
		)
		(property "Public" "False"
			(at 0 0 0)
			(unlocked yes)
			(layer "B.Fab")
			(hide yes)
			(effects
				(font
					(size 1 1)
					(thickness 0.15)
				)
				(justify mirror)
			)
		)
		(sheetname "/M.2/")
		(sheetfile "m2.kicad_sch")
		(attr smd)
		(fp_rect
			(start -0.925 0.47)
			(end 0.925 -0.47)
			(stroke
				(width 0.05)
				(type default)
			)
			(fill no)
			(layer "B.CrtYd")
		)
		(fp_line
			(start -0.494 -0.248)
			(end -0.494 0.25)
			(stroke
				(width 0.15)
				(type solid)
			)
			(layer "B.Fab")
		)
		(fp_line
			(start -0.494 0.25)
			(end 0.504 0.25)
			(stroke
				(width 0.15)
				(type solid)
			)
			(layer "B.Fab")
		)
		(fp_line
			(start 0.504 -0.248)
			(end -0.494 -0.248)
			(stroke
				(width 0.15)
				(type solid)
			)
			(layer "B.Fab")
		)
		(fp_line
			(start 0.504 0.25)
			(end 0.504 -0.248)
			(stroke
				(width 0.15)
				(type solid)
			)
			(layer "B.Fab")
		)
		(fp_text user "License: Apache-2.0"
			(at -0.939 -5.799 180)
			(layer "B.Fab")
			(effects
				(font
					(size 0.7 0.7)
					(thickness 0.15)
				)
				(justify left bottom mirror)
			)
		)
		(fp_text user "Author: Antmicro"
			(at -0.939 -3.399 180)
			(layer "B.Fab")
			(effects
				(font
					(size 0.7 0.7)
					(thickness 0.15)
				)
				(justify left bottom mirror)
			)
		)
		(fp_text user "${REFERENCE}"
			(at -0.939 -4.599 180)
			(layer "B.Fab")
			(effects
				(font
					(size 0.7 0.7)
					(thickness 0.15)
				)
				(justify left bottom mirror)
			)
		)
		(pad "1" smd roundrect
			(at -0.48 0)
			(size 0.59 0.64)
			(layers "B.Cu" "B.Mask" "B.Paste")
			(roundrect_rratio 0.25)
			(net 382 "/M.2/PCIe_{C5x4}.TX0+")
			(pintype "passive")
		)
		(pad "2" smd roundrect
			(at 0.48 0)
			(size 0.59 0.64)
			(layers "B.Cu" "B.Mask" "B.Paste")
			(roundrect_rratio 0.25)
			(net 386 "/M.2/M2_M_PET0_P")
			(pintype "passive")
		)
	)
	(footprint "antmicro-footprints:C_0603_1608Metric_EIA"
		(layer "B.Cu")
		(at 124.6 120 180)
		(descr "Capacitor SMD 0603, IPC-7351 Density Level A")
		(tags "Capacitor 0603")
		(property "Reference" "C71"
			(at -3.47 -0.415 0)
			(layer "B.SilkS")
			(effects
				(font
					(size 0.7 0.7)
					(thickness 0.15)
				)
				(justify left bottom mirror)
			)
		)
		(property "Value" "C_22u_16V_0603"
			(at -1.42757 -1.770288 0)
			(layer "B.Fab")
			(effects
				(font
					(size 0.7 0.7)
					(thickness 0.15)
				)
				(justify left bottom mirror)
			)
		)
		(property "Datasheet" "https://product.samsungsem.com/mlcc/CL10A226MO7JZN.do"
			(at 0 0 0)
			(layer "B.Fab")
			(hide yes)
			(effects
				(font
					(size 1.27 1.27)
					(thickness 0.15)
				)
				(justify mirror)
			)
		)
		(property "Description" "SMD Multilayer Ceramic Capacitor"
			(at 0 0 0)
			(layer "B.Fab")
			(hide yes)
			(effects
				(font
					(size 1.27 1.27)
					(thickness 0.15)
				)
				(justify mirror)
			)
		)
		(property "MPN" "CL10A226MO7JZNC"
			(at 0 0 180)
			(unlocked yes)
			(layer "B.Fab")
			(hide yes)
			(effects
				(font
					(size 1 1)
					(thickness 0.15)
				)
				(justify mirror)
			)
		)
		(property "Manufacturer" "Samsung Electro-Mechanics"
			(at 0 0 180)
			(unlocked yes)
			(layer "B.Fab")
			(hide yes)
			(effects
				(font
					(size 1 1)
					(thickness 0.15)
				)
				(justify mirror)
			)
		)
		(property "License" "Apache-2.0"
			(at 0 0 180)
			(unlocked yes)
			(layer "B.Fab")
			(hide yes)
			(effects
				(font
					(size 1 1)
					(thickness 0.15)
				)
				(justify mirror)
			)
		)
		(property "Author" "Antmicro"
			(at 0 0 180)
			(unlocked yes)
			(layer "B.Fab")
			(hide yes)
			(effects
				(font
					(size 1 1)
					(thickness 0.15)
				)
				(justify mirror)
			)
		)
		(property "Val" "22u"
			(at 0 0 180)
			(unlocked yes)
			(layer "B.Fab")
			(hide yes)
			(effects
				(font
					(size 1 1)
					(thickness 0.15)
				)
				(justify mirror)
			)
		)
		(property "Voltage" "16V"
			(at 0 0 180)
			(unlocked yes)
			(layer "B.Fab")
			(hide yes)
			(effects
				(font
					(size 1 1)
					(thickness 0.15)
				)
				(justify mirror)
			)
		)
		(property "Dielectric" ""
			(at 0 0 180)
			(unlocked yes)
			(layer "B.Fab")
			(hide yes)
			(effects
				(font
					(size 1 1)
					(thickness 0.15)
				)
				(justify mirror)
			)
		)
		(sheetname "/M.2/")
		(sheetfile "m2.kicad_sch")
		(attr smd)
		(fp_line
			(start -0.15 0.55)
			(end 0.15 0.55)
			(stroke
				(width 0.15)
				(type solid)
			)
			(layer "B.SilkS")
		)
		(fp_line
			(start -0.15 -0.55)
			(end 0.15 -0.55)
			(stroke
				(width 0.15)
				(type solid)
			)
			(layer "B.SilkS")
		)
		(fp_rect
			(start -1.25 0.65)
			(end 1.25 -0.65)
			(stroke
				(width 0.05)
				(type solid)
			)
			(fill no)
			(layer "B.CrtYd")
		)
		(fp_rect
			(start -0.8 0.45)
			(end 0.8 -0.45)
			(stroke
				(width 0.15)
				(type solid)
			)
			(fill no)
			(layer "B.Fab")
		)
		(fp_text user "License: Apache-2.0"
			(at -1.682 -5.895 0)
			(layer "B.Fab")
			(effects
				(font
					(size 0.7 0.7)
					(thickness 0.15)
				)
				(justify left bottom mirror)
			)
		)
		(fp_text user "${REFERENCE}"
			(at -1.682 -3.895 0)
			(layer "B.Fab")
			(effects
				(font
					(size 0.7 0.7)
					(thickness 0.15)
				)
				(justify left bottom mirror)
			)
		)
		(fp_text user "Author: Antmicro"
			(at -1.682 -4.894 0)
			(layer "B.Fab")
			(effects
				(font
					(size 0.7 0.7)
					(thickness 0.15)
				)
				(justify left bottom mirror)
			)
		)
		(pad "1" smd roundrect
			(at -0.7 0 180)
			(size 0.8 1.1)
			(layers "B.Cu" "B.Mask" "B.Paste")
			(roundrect_rratio 0.2)
			(net 1 "GND")
			(pintype "passive")
		)
		(pad "2" smd roundrect
			(at 0.7 0 180)
			(size 0.8 1.1)
			(layers "B.Cu" "B.Mask" "B.Paste")
			(roundrect_rratio 0.2)
			(net 2 "+3V3")
			(pintype "passive")
		)
	)
	(footprint "antmicro-footprints:TP_SMD_0.75mm"
		(layer "B.Cu")
		(at 141.730532 71.31 90)
		(property "Reference" "TP60"
			(at -3.29 -0.430532 90)
			(layer "B.SilkS")
			(effects
				(font
					(size 0.7 0.7)
					(thickness 0.15)
				)
				(justify right top mirror)
			)
		)
		(property "Value" "TP_0.75mm_SMD"
			(at 0 -1.2 90)
			(layer "B.Fab")
			(effects
				(font
					(size 0.7 0.7)
					(thickness 0.15)
				)
				(justify right top mirror)
			)
		)
		(property "Description" "SMT test point"
			(at 0 0 90)
			(layer "B.Fab")
			(hide yes)
			(effects
				(font
					(size 1.27 1.27)
					(thickness 0.15)
				)
				(justify mirror)
			)
		)
		(property "MPN" ""
			(at 0 0 270)
			(unlocked yes)
			(layer "B.Fab")
			(hide yes)
			(effects
				(font
					(size 1 1)
					(thickness 0.15)
				)
				(justify mirror)
			)
		)
		(property "Manufacturer" ""
			(at 0 0 270)
			(unlocked yes)
			(layer "B.Fab")
			(hide yes)
			(effects
				(font
					(size 1 1)
					(thickness 0.15)
				)
				(justify mirror)
			)
		)
		(property "Author" "Antmicro"
			(at 0 0 270)
			(unlocked yes)
			(layer "B.Fab")
			(hide yes)
			(effects
				(font
					(size 1 1)
					(thickness 0.15)
				)
				(justify mirror)
			)
		)
		(property "License" "Apache-2.0"
			(at 0 0 270)
			(unlocked yes)
			(layer "B.Fab")
			(hide yes)
			(effects
				(font
					(size 1 1)
					(thickness 0.15)
				)
				(justify mirror)
			)
		)
		(sheetname "/SoM_Power/")
		(sheetfile "som_power.kicad_sch")
		(attr exclude_from_pos_files exclude_from_bom)
		(fp_circle
			(center 0 0)
			(end 0.475 0)
			(stroke
				(width 0.05)
				(type default)
			)
			(fill no)
			(layer "B.CrtYd")
		)
		(fp_text user "Author: Antmicro"
			(at -0.4 -3.901 90)
			(layer "B.Fab")
			(effects
				(font
					(size 0.7 0.7)
					(thickness 0.15)
				)
				(justify right top mirror)
			)
		)
		(fp_text user "License: Apache-2.0"
			(at -0.4 -5.101 90)
			(layer "B.Fab")
			(effects
				(font
					(size 0.7 0.7)
					(thickness 0.15)
				)
				(justify right top mirror)
			)
		)
		(fp_text user "${REFERENCE}"
			(at -0.4 -2.7 90)
			(layer "B.Fab")
			(effects
				(font
					(size 0.7 0.7)
					(thickness 0.15)
				)
				(justify right top mirror)
			)
		)
		(pad "1" smd circle
			(at 0 0 90)
			(size 0.75 0.75)
			(layers "B.Cu" "B.Mask")
			(net 760 "Net-(J1A-MODULE_POWER_GOOD)")
			(pinfunction "1")
			(pintype "passive")
		)
	)
	(footprint "antmicro-footprints:R_0603_1608Metric"
		(layer "B.Cu")
		(at 100.1 133.9 180)
		(descr "Resistor SMD 0603")
		(tags "resistor SMD 0603")
		(property "Reference" "R33"
			(at -3.4 -0.5 0)
			(layer "B.SilkS")
			(effects
				(font
					(size 0.7 0.7)
					(thickness 0.15)
				)
				(justify left bottom mirror)
			)
		)
		(property "Value" "R_0R_22.4A_0603"
			(at 0 -1.6 0)
			(layer "B.Fab")
			(effects
				(font
					(size 0.7 0.7)
					(thickness 0.15)
				)
				(justify left bottom mirror)
			)
		)
		(property "Datasheet" "https://fscdn.rohm.com/en/products/databook/datasheet/passive/resistor/chip_resistor/pmr-jpw-e.pdf"
			(at 0 0 0)
			(layer "B.Fab")
			(hide yes)
			(effects
				(font
					(size 1.27 1.27)
					(thickness 0.15)
				)
				(justify mirror)
			)
		)
		(property "Description" "SMD Chip Resistor"
			(at 0 0 0)
			(layer "B.Fab")
			(hide yes)
			(effects
				(font
					(size 1.27 1.27)
					(thickness 0.15)
				)
				(justify mirror)
			)
		)
		(property "MPN" "PMR03EZPJ000"
			(at 0 0 0)
			(unlocked yes)
			(layer "B.Fab")
			(hide yes)
			(effects
				(font
					(size 1 1)
					(thickness 0.15)
				)
				(justify mirror)
			)
		)
		(property "Manufacturer" "ROHM Semiconductor"
			(at 0 0 0)
			(unlocked yes)
			(layer "B.Fab")
			(hide yes)
			(effects
				(font
					(size 1 1)
					(thickness 0.15)
				)
				(justify mirror)
			)
		)
		(property "Val" "0R"
			(at 0 0 0)
			(unlocked yes)
			(layer "B.Fab")
			(hide yes)
			(effects
				(font
					(size 1 1)
					(thickness 0.15)
				)
				(justify mirror)
			)
		)
		(property "Max. Curr." "22.4A"
			(at 0 0 0)
			(unlocked yes)
			(layer "B.Fab")
			(hide yes)
			(effects
				(font
					(size 1 1)
					(thickness 0.15)
				)
				(justify mirror)
			)
		)
		(property "Author" "Antmicro"
			(at 0 0 0)
			(unlocked yes)
			(layer "B.Fab")
			(hide yes)
			(effects
				(font
					(size 1 1)
					(thickness 0.15)
				)
				(justify mirror)
			)
		)
		(property "License" "Apache-2.0"
			(at 0 0 0)
			(unlocked yes)
			(layer "B.Fab")
			(hide yes)
			(effects
				(font
					(size 1 1)
					(thickness 0.15)
				)
				(justify mirror)
			)
		)
		(property "Tolerance" "template_tolerance"
			(at 0 0 0)
			(unlocked yes)
			(layer "B.Fab")
			(hide yes)
			(effects
				(font
					(size 1 1)
					(thickness 0.15)
				)
				(justify mirror)
			)
		)
		(sheetname "/Expansion connector/")
		(sheetfile "expansion_connector.kicad_sch")
		(attr smd exclude_from_pos_files exclude_from_bom dnp)
		(fp_line
			(start -0.15 0.4)
			(end 0.15 0.4)
			(stroke
				(width 0.15)
				(type solid)
			)
			(layer "B.SilkS")
		)
		(fp_line
			(start -0.15 -0.4)
			(end 0.15 -0.4)
			(stroke
				(width 0.15)
				(type solid)
			)
			(layer "B.SilkS")
		)
		(fp_rect
			(start -1.25 0.65)
			(end 1.25 -0.65)
			(stroke
				(width 0.05)
				(type solid)
			)
			(fill no)
			(layer "B.CrtYd")
		)
		(fp_rect
			(start -0.8 0.4)
			(end 0.8 -0.4)
			(stroke
				(width 0.15)
				(type solid)
			)
			(fill no)
			(layer "B.Fab")
		)
		(fp_text user "License: Apache-2.0"
			(at -1.25 -5.9 0)
			(layer "B.Fab")
			(effects
				(font
					(size 0.7 0.7)
					(thickness 0.15)
				)
				(justify left bottom mirror)
			)
		)
		(fp_text user "Author: Antmicro"
			(at -1.25 -4.9 0)
			(layer "B.Fab")
			(effects
				(font
					(size 0.7 0.7)
					(thickness 0.15)
				)
				(justify left bottom mirror)
			)
		)
		(fp_text user "${REFERENCE}"
			(at -1.25 -3.898 0)
			(layer "B.Fab")
			(effects
				(font
					(size 0.7 0.7)
					(thickness 0.15)
				)
				(justify left bottom mirror)
			)
		)
		(pad "1" smd roundrect
			(at -0.7 0 180)
			(size 0.8 1)
			(layers "B.Cu" "B.Mask" "B.Paste")
			(roundrect_rratio 0.2)
			(net 13 "VCC")
			(pintype "passive")
		)
		(pad "2" smd roundrect
			(at 0.7 0 180)
			(size 0.8 1)
			(layers "B.Cu" "B.Mask" "B.Paste")
			(roundrect_rratio 0.2)
			(net 156 "/Expansion connector/+VCC_FMC")
			(pintype "passive")
		)
	)
	(footprint "antmicro-footprints:TP_SMD_0.75mm"
		(layer "B.Cu")
		(at 205.966532 142.82 -90)
		(property "Reference" "TP29"
			(at -2.13 0.600532 90)
			(layer "B.SilkS")
			(effects
				(font
					(size 0.7 0.7)
					(thickness 0.15)
				)
				(justify left bottom mirror)
			)
		)
		(property "Value" "TP_0.75mm_SMD"
			(at 0 -1.2 90)
			(layer "B.Fab")
			(effects
				(font
					(size 0.7 0.7)
					(thickness 0.15)
				)
				(justify left bottom mirror)
			)
		)
		(property "Description" "SMT test point"
			(at 0 0 90)
			(layer "B.Fab")
			(hide yes)
			(effects
				(font
					(size 1.27 1.27)
					(thickness 0.15)
				)
				(justify mirror)
			)
		)
		(property "MPN" ""
			(at 0 0 90)
			(unlocked yes)
			(layer "B.Fab")
			(hide yes)
			(effects
				(font
					(size 1 1)
					(thickness 0.15)
				)
				(justify mirror)
			)
		)
		(property "Manufacturer" ""
			(at 0 0 90)
			(unlocked yes)
			(layer "B.Fab")
			(hide yes)
			(effects
				(font
					(size 1 1)
					(thickness 0.15)
				)
				(justify mirror)
			)
		)
		(property "Author" "Antmicro"
			(at 0 0 90)
			(unlocked yes)
			(layer "B.Fab")
			(hide yes)
			(effects
				(font
					(size 1 1)
					(thickness 0.15)
				)
				(justify mirror)
			)
		)
		(property "License" "Apache-2.0"
			(at 0 0 90)
			(unlocked yes)
			(layer "B.Fab")
			(hide yes)
			(effects
				(font
					(size 1 1)
					(thickness 0.15)
				)
				(justify mirror)
			)
		)
		(sheetname "/SFP/")
		(sheetfile "sfp.kicad_sch")
		(attr exclude_from_pos_files exclude_from_bom)
		(fp_circle
			(center 0 0)
			(end 0.475 0)
			(stroke
				(width 0.05)
				(type default)
			)
			(fill no)
			(layer "B.CrtYd")
		)
		(fp_text user "Author: Antmicro"
			(at -0.4 -3.901 90)
			(layer "B.Fab")
			(effects
				(font
					(size 0.7 0.7)
					(thickness 0.15)
				)
				(justify left bottom mirror)
			)
		)
		(fp_text user "${REFERENCE}"
			(at -0.4 -2.7 90)
			(layer "B.Fab")
			(effects
				(font
					(size 0.7 0.7)
					(thickness 0.15)
				)
				(justify left bottom mirror)
			)
		)
		(fp_text user "License: Apache-2.0"
			(at -0.4 -5.101 90)
			(layer "B.Fab")
			(effects
				(font
					(size 0.7 0.7)
					(thickness 0.15)
				)
				(justify left bottom mirror)
			)
		)
		(pad "1" smd circle
			(at 0 0 270)
			(size 0.75 0.75)
			(layers "B.Cu" "B.Mask")
			(net 1370 "Net-(J12-RX_{LOS})")
			(pinfunction "1")
			(pintype "passive")
		)
	)
	(footprint "antmicro-footprints:TP_SMD_0.75mm"
		(layer "B.Cu")
		(at 167.39 58 180)
		(property "Reference" "TP132"
			(at -0.43 4.05 90)
			(layer "B.SilkS")
			(effects
				(font
					(size 0.7 0.7)
					(thickness 0.15)
				)
				(justify left bottom mirror)
			)
		)
		(property "Value" "TP_0.75mm_SMD"
			(at 0 -1.2 0)
			(layer "B.Fab")
			(effects
				(font
					(size 0.7 0.7)
					(thickness 0.15)
				)
				(justify left bottom mirror)
			)
		)
		(property "Description" "SMT test point"
			(at 0 0 0)
			(layer "B.Fab")
			(hide yes)
			(effects
				(font
					(size 1.27 1.27)
					(thickness 0.15)
				)
				(justify mirror)
			)
		)
		(property "MPN" ""
			(at 0 0 0)
			(unlocked yes)
			(layer "B.Fab")
			(hide yes)
			(effects
				(font
					(size 1 1)
					(thickness 0.15)
				)
				(justify mirror)
			)
		)
		(property "Manufacturer" ""
			(at 0 0 0)
			(unlocked yes)
			(layer "B.Fab")
			(hide yes)
			(effects
				(font
					(size 1 1)
					(thickness 0.15)
				)
				(justify mirror)
			)
		)
		(property "Author" "Antmicro"
			(at 0 0 0)
			(unlocked yes)
			(layer "B.Fab")
			(hide yes)
			(effects
				(font
					(size 1 1)
					(thickness 0.15)
				)
				(justify mirror)
			)
		)
		(property "License" "Apache-2.0"
			(at 0 0 0)
			(unlocked yes)
			(layer "B.Fab")
			(hide yes)
			(effects
				(font
					(size 1 1)
					(thickness 0.15)
				)
				(justify mirror)
			)
		)
		(sheetname "/Power/")
		(sheetfile "power.kicad_sch")
		(attr exclude_from_pos_files exclude_from_bom)
		(fp_circle
			(center 0 0)
			(end 0.475 0)
			(stroke
				(width 0.05)
				(type default)
			)
			(fill no)
			(layer "B.CrtYd")
		)
		(fp_text user "Author: Antmicro"
			(at -0.4 -3.901 0)
			(layer "B.Fab")
			(effects
				(font
					(size 0.7 0.7)
					(thickness 0.15)
				)
				(justify left bottom mirror)
			)
		)
		(fp_text user "${REFERENCE}"
			(at -0.4 -2.7 0)
			(layer "B.Fab")
			(effects
				(font
					(size 0.7 0.7)
					(thickness 0.15)
				)
				(justify left bottom mirror)
			)
		)
		(fp_text user "License: Apache-2.0"
			(at -0.4 -5.101 0)
			(layer "B.Fab")
			(effects
				(font
					(size 0.7 0.7)
					(thickness 0.15)
				)
				(justify left bottom mirror)
			)
		)
		(pad "1" smd circle
			(at 0 0 180)
			(size 0.75 0.75)
			(layers "B.Cu" "B.Mask")
			(net 2 "+3V3")
			(pinfunction "1")
			(pintype "passive")
		)
	)
)
